(kicad_pcb
	(version 20260206)
	(generator "pcbnew")
	(generator_version "10.0")
	(general
		(thickness 1.6)
		(legacy_teardrops no)
	)
	(paper "A4")
	(title_block
		(title "03242023_DA0F0TMBIJ0_F0T_Motherboard_J_brd_V01_OCP.brd")
		(comment 1 "Grand Teton / footprint 1229 of 6105 (J4), pads 225-291 of 291")
	)
	(layers
		(0 "F.Cu" signal "TOP")
		(4 "In1.Cu" signal "GND")
		(6 "In2.Cu" signal "IN1")
		(8 "In3.Cu" signal "GND1")
		(10 "In4.Cu" signal "IN2")
		(12 "In5.Cu" signal "GND2")
		(14 "In6.Cu" signal "IN3")
		(16 "In7.Cu" signal "GND3")
		(18 "In8.Cu" signal "VCC")
		(20 "In9.Cu" signal "VCC1")
		(22 "In10.Cu" signal "GND4")
		(24 "In11.Cu" signal "IN4")
		(26 "In12.Cu" signal "GND5")
		(28 "In13.Cu" signal "IN5")
		(30 "In14.Cu" signal "GND6")
		(32 "In15.Cu" signal "IN6")
		(34 "In16.Cu" signal "GND7")
		(2 "B.Cu" signal "BOTTOM")
		(9 "F.Adhes" user "F.Adhesive")
		(11 "B.Adhes" user "B.Adhesive")
		(13 "F.Paste" user "Package Geometry/Pastemask Top")
		(15 "B.Paste" user "Package Geometry/Pastemask Bottom")
		(5 "F.SilkS" user "Ref Des/Silkscreen Top")
		(7 "B.SilkS" user "Ref Des/Silkscreen Bottom")
		(1 "F.Mask" user "Board Geometry/Soldermask Top")
		(3 "B.Mask" user "Board Geometry/Soldermask Bottom")
		(17 "Dwgs.User" user "User.Drawings")
		(19 "Cmts.User" user "User.Comments")
		(21 "Eco1.User" user "User.Eco1")
		(23 "Eco2.User" user "User.Eco2")
		(25 "Edge.Cuts" user "Board Geometry/Outline")
		(27 "Margin" user)
		(31 "F.CrtYd" user "Package Geometry/Place Bound Top")
		(29 "B.CrtYd" user "Package Geometry/Place Bound Bottom")
		(35 "F.Fab" user "Ref Des/Assembly Top")
		(33 "B.Fab" user "Ref Des/Assembly Bottom")
	)
	(footprint ""
		(layer "F.Cu")
		(at 295.849548 -258.091686)
		(property "Reference" "J4"
			(at -3.683 -81.702148 0)
			(unlocked yes)
			(layer "F.SilkS")
			(effects
				(font
					(size 0.7874 0.5842)
					(thickness 0.1524)
				)
				(justify left)
			)
		)
		(property "Value" ""
			(at 0 0 0)
			(layer "F.Fab")
			(effects
				(font
					(size 1.27 1.27)
				)
			)
		)
		(duplicate_pad_numbers_are_jumpers no)
		(pad "225" smd rect
			(at 2.050034 9.774936 270)
			(size 0.519938 1.4986)
			(layers "F.Cu" "F.Mask" "F.Paste")
			(net "M_B_CPU0_SB_CA<5>")
		)
		(pad "226" smd rect
			(at 2.050034 10.625074 270)
			(size 0.519938 1.4986)
			(layers "F.Cu" "F.Mask" "F.Paste")
			(net "GND")
		)
		(pad "227" smd rect
			(at 2.050034 11.474958 270)
			(size 0.519938 1.4986)
			(layers "F.Cu" "F.Mask" "F.Paste")
			(net "M_B_CPU0_SB_PAR")
		)
		(pad "228" smd rect
			(at 2.050034 12.325096 270)
			(size 0.519938 1.4986)
			(layers "F.Cu" "F.Mask" "F.Paste")
			(net "GND")
		)
		(pad "229" smd rect
			(at 2.050034 13.17498 270)
			(size 0.519938 1.4986)
			(layers "F.Cu" "F.Mask" "F.Paste")
			(net "M_B_CPU0_SB_CS_N<3>")
		)
		(pad "230" smd rect
			(at 2.050034 14.025118 270)
			(size 0.519938 1.4986)
			(layers "F.Cu" "F.Mask" "F.Paste")
			(net "GND")
		)
		(pad "231" smd rect
			(at 2.050034 14.875002 270)
			(size 0.519938 1.4986)
			(layers "F.Cu" "F.Mask" "F.Paste")
			(net "TP_CHB_CPU0_DIMM2_FRU_5")
		)
		(pad "232" smd rect
			(at 2.050034 15.724886 270)
			(size 0.519938 1.4986)
			(layers "F.Cu" "F.Mask" "F.Paste")
			(net "TP_CHB_CPU0_DIMM2_FRU_6")
		)
		(pad "233" smd rect
			(at 2.050034 16.575024 270)
			(size 0.519938 1.4986)
			(layers "F.Cu" "F.Mask" "F.Paste")
			(net "GND")
		)
		(pad "234" smd rect
			(at 2.050034 17.424908 270)
			(size 0.519938 1.4986)
			(layers "F.Cu" "F.Mask" "F.Paste")
			(net "M_B_CPU0_SB_CB<6>")
		)
		(pad "235" smd rect
			(at 2.050034 18.275046 270)
			(size 0.519938 1.4986)
			(layers "F.Cu" "F.Mask" "F.Paste")
			(net "GND")
		)
		(pad "236" smd rect
			(at 2.050034 19.12493 270)
			(size 0.519938 1.4986)
			(layers "F.Cu" "F.Mask" "F.Paste")
			(net "M_B_CPU0_SB_CB<7>")
		)
		(pad "237" smd rect
			(at 2.050034 19.975068 270)
			(size 0.519938 1.4986)
			(layers "F.Cu" "F.Mask" "F.Paste")
			(net "GND")
		)
		(pad "238" smd rect
			(at 2.050034 20.824952 270)
			(size 0.519938 1.4986)
			(layers "F.Cu" "F.Mask" "F.Paste")
			(net "M_B_CPU0_SB_DQS_DN<4>")
		)
		(pad "239" smd rect
			(at 2.050034 21.67509 270)
			(size 0.519938 1.4986)
			(layers "F.Cu" "F.Mask" "F.Paste")
			(net "M_B_CPU0_SB_DQS_DP<4>")
		)
		(pad "240" smd rect
			(at 2.050034 22.524974 270)
			(size 0.519938 1.4986)
			(layers "F.Cu" "F.Mask" "F.Paste")
			(net "GND")
		)
		(pad "241" smd rect
			(at 2.050034 23.375112 270)
			(size 0.519938 1.4986)
			(layers "F.Cu" "F.Mask" "F.Paste")
			(net "M_B_CPU0_SB_CB<2>")
		)
		(pad "242" smd rect
			(at 2.050034 24.224996 270)
			(size 0.519938 1.4986)
			(layers "F.Cu" "F.Mask" "F.Paste")
			(net "GND")
		)
		(pad "243" smd rect
			(at 2.050034 25.07488 270)
			(size 0.519938 1.4986)
			(layers "F.Cu" "F.Mask" "F.Paste")
			(net "M_B_CPU0_SB_CB<3>")
		)
		(pad "244" smd rect
			(at 2.050034 25.925018 270)
			(size 0.519938 1.4986)
			(layers "F.Cu" "F.Mask" "F.Paste")
			(net "GND")
		)
		(pad "245" smd rect
			(at 2.050034 26.774902 270)
			(size 0.519938 1.4986)
			(layers "F.Cu" "F.Mask" "F.Paste")
			(net "M_B_CPU0_SB_DQ<2>")
		)
		(pad "246" smd rect
			(at 2.050034 27.62504 270)
			(size 0.519938 1.4986)
			(layers "F.Cu" "F.Mask" "F.Paste")
			(net "GND")
		)
		(pad "247" smd rect
			(at 2.050034 28.474924 270)
			(size 0.519938 1.4986)
			(layers "F.Cu" "F.Mask" "F.Paste")
			(net "M_B_CPU0_SB_DQ<3>")
		)
		(pad "248" smd rect
			(at 2.050034 29.325062 270)
			(size 0.519938 1.4986)
			(layers "F.Cu" "F.Mask" "F.Paste")
			(net "GND")
		)
		(pad "249" smd rect
			(at 2.050034 30.174946 270)
			(size 0.519938 1.4986)
			(layers "F.Cu" "F.Mask" "F.Paste")
			(net "M_B_CPU0_SB_DQS_DN<5>")
		)
		(pad "250" smd rect
			(at 2.050034 31.025084 270)
			(size 0.519938 1.4986)
			(layers "F.Cu" "F.Mask" "F.Paste")
			(net "M_B_CPU0_SB_DQS_DP<5>")
		)
		(pad "251" smd rect
			(at 2.050034 31.874968 270)
			(size 0.519938 1.4986)
			(layers "F.Cu" "F.Mask" "F.Paste")
			(net "GND")
		)
		(pad "252" smd rect
			(at 2.050034 32.725106 270)
			(size 0.519938 1.4986)
			(layers "F.Cu" "F.Mask" "F.Paste")
			(net "M_B_CPU0_SB_DQ<6>")
		)
		(pad "253" smd rect
			(at 2.050034 33.57499 270)
			(size 0.519938 1.4986)
			(layers "F.Cu" "F.Mask" "F.Paste")
			(net "GND")
		)
		(pad "254" smd rect
			(at 2.050034 34.425128 270)
			(size 0.519938 1.4986)
			(layers "F.Cu" "F.Mask" "F.Paste")
			(net "M_B_CPU0_SB_DQ<7>")
		)
		(pad "255" smd rect
			(at 2.050034 35.275012 270)
			(size 0.519938 1.4986)
			(layers "F.Cu" "F.Mask" "F.Paste")
			(net "GND")
		)
		(pad "256" smd rect
			(at 2.050034 36.124896 270)
			(size 0.519938 1.4986)
			(layers "F.Cu" "F.Mask" "F.Paste")
			(net "M_B_CPU0_SB_DQ<10>")
		)
		(pad "257" smd rect
			(at 2.050034 36.975034 270)
			(size 0.519938 1.4986)
			(layers "F.Cu" "F.Mask" "F.Paste")
			(net "GND")
		)
		(pad "258" smd rect
			(at 2.050034 37.824918 270)
			(size 0.519938 1.4986)
			(layers "F.Cu" "F.Mask" "F.Paste")
			(net "M_B_CPU0_SB_DQ<11>")
		)
		(pad "259" smd rect
			(at 2.050034 38.675056 270)
			(size 0.519938 1.4986)
			(layers "F.Cu" "F.Mask" "F.Paste")
			(net "GND")
		)
		(pad "260" smd rect
			(at 2.050034 39.52494 270)
			(size 0.519938 1.4986)
			(layers "F.Cu" "F.Mask" "F.Paste")
			(net "M_B_CPU0_SB_DQS_DN<6>")
		)
		(pad "261" smd rect
			(at 2.050034 40.375078 270)
			(size 0.519938 1.4986)
			(layers "F.Cu" "F.Mask" "F.Paste")
			(net "M_B_CPU0_SB_DQS_DP<6>")
		)
		(pad "262" smd rect
			(at 2.050034 41.224962 270)
			(size 0.519938 1.4986)
			(layers "F.Cu" "F.Mask" "F.Paste")
			(net "GND")
		)
		(pad "263" smd rect
			(at 2.050034 42.0751 270)
			(size 0.519938 1.4986)
			(layers "F.Cu" "F.Mask" "F.Paste")
			(net "M_B_CPU0_SB_DQ<14>")
		)
		(pad "264" smd rect
			(at 2.050034 42.924984 270)
			(size 0.519938 1.4986)
			(layers "F.Cu" "F.Mask" "F.Paste")
			(net "GND")
		)
		(pad "265" smd rect
			(at 2.050034 43.775122 270)
			(size 0.519938 1.4986)
			(layers "F.Cu" "F.Mask" "F.Paste")
			(net "M_B_CPU0_SB_DQ<15>")
		)
		(pad "266" smd rect
			(at 2.050034 44.625006 270)
			(size 0.519938 1.4986)
			(layers "F.Cu" "F.Mask" "F.Paste")
			(net "GND")
		)
		(pad "267" smd rect
			(at 2.050034 45.47489 270)
			(size 0.519938 1.4986)
			(layers "F.Cu" "F.Mask" "F.Paste")
			(net "M_B_CPU0_SB_DQ<18>")
		)
		(pad "268" smd rect
			(at 2.050034 46.325028 270)
			(size 0.519938 1.4986)
			(layers "F.Cu" "F.Mask" "F.Paste")
			(net "GND")
		)
		(pad "269" smd rect
			(at 2.050034 47.174912 270)
			(size 0.519938 1.4986)
			(layers "F.Cu" "F.Mask" "F.Paste")
			(net "M_B_CPU0_SB_DQ<19>")
		)
		(pad "270" smd rect
			(at 2.050034 48.02505 270)
			(size 0.519938 1.4986)
			(layers "F.Cu" "F.Mask" "F.Paste")
			(net "GND")
		)
		(pad "271" smd rect
			(at 2.050034 48.874934 270)
			(size 0.519938 1.4986)
			(layers "F.Cu" "F.Mask" "F.Paste")
			(net "M_B_CPU0_SB_DQS_DN<7>")
		)
		(pad "272" smd rect
			(at 2.050034 49.725072 270)
			(size 0.519938 1.4986)
			(layers "F.Cu" "F.Mask" "F.Paste")
			(net "M_B_CPU0_SB_DQS_DP<7>")
		)
		(pad "273" smd rect
			(at 2.050034 50.574956 270)
			(size 0.519938 1.4986)
			(layers "F.Cu" "F.Mask" "F.Paste")
			(net "GND")
		)
		(pad "274" smd rect
			(at 2.050034 51.425094 270)
			(size 0.519938 1.4986)
			(layers "F.Cu" "F.Mask" "F.Paste")
			(net "M_B_CPU0_SB_DQ<22>")
		)
		(pad "275" smd rect
			(at 2.050034 52.274978 270)
			(size 0.519938 1.4986)
			(layers "F.Cu" "F.Mask" "F.Paste")
			(net "GND")
		)
		(pad "276" smd rect
			(at 2.050034 53.125116 270)
			(size 0.519938 1.4986)
			(layers "F.Cu" "F.Mask" "F.Paste")
			(net "M_B_CPU0_SB_DQ<23>")
		)
		(pad "277" smd rect
			(at 2.050034 53.975 270)
			(size 0.519938 1.4986)
			(layers "F.Cu" "F.Mask" "F.Paste")
			(net "GND")
		)
		(pad "278" smd rect
			(at 2.050034 54.824884 270)
			(size 0.519938 1.4986)
			(layers "F.Cu" "F.Mask" "F.Paste")
			(net "M_B_CPU0_SB_DQ<26>")
		)
		(pad "279" smd rect
			(at 2.050034 55.675022 270)
			(size 0.519938 1.4986)
			(layers "F.Cu" "F.Mask" "F.Paste")
			(net "GND")
		)
		(pad "280" smd rect
			(at 2.050034 56.524906 270)
			(size 0.519938 1.4986)
			(layers "F.Cu" "F.Mask" "F.Paste")
			(net "M_B_CPU0_SB_DQ<27>")
		)
		(pad "281" smd rect
			(at 2.050034 57.375044 270)
			(size 0.519938 1.4986)
			(layers "F.Cu" "F.Mask" "F.Paste")
			(net "GND")
		)
		(pad "282" smd rect
			(at 2.050034 58.224928 270)
			(size 0.519938 1.4986)
			(layers "F.Cu" "F.Mask" "F.Paste")
			(net "M_B_CPU0_SB_DQS_DN<8>")
		)
		(pad "283" smd rect
			(at 2.050034 59.075066 270)
			(size 0.519938 1.4986)
			(layers "F.Cu" "F.Mask" "F.Paste")
			(net "M_B_CPU0_SB_DQS_DP<8>")
		)
		(pad "284" smd rect
			(at 2.050034 59.92495 270)
			(size 0.519938 1.4986)
			(layers "F.Cu" "F.Mask" "F.Paste")
			(net "GND")
		)
		(pad "285" smd rect
			(at 2.050034 60.775088 270)
			(size 0.519938 1.4986)
			(layers "F.Cu" "F.Mask" "F.Paste")
			(net "M_B_CPU0_SB_DQ<30>")
		)
		(pad "286" smd rect
			(at 2.050034 61.624972 270)
			(size 0.519938 1.4986)
			(layers "F.Cu" "F.Mask" "F.Paste")
			(net "GND")
		)
		(pad "287" smd rect
			(at 2.050034 62.47511 270)
			(size 0.519938 1.4986)
			(layers "F.Cu" "F.Mask" "F.Paste")
			(net "M_B_CPU0_SB_DQ<31>")
		)
		(pad "288" smd rect
			(at 2.050034 63.324994 270)
			(size 0.519938 1.4986)
			(layers "F.Cu" "F.Mask" "F.Paste")
			(net "GND")
		)
		(pad "G1" thru_hole oval
			(at 0 -68.97497)
			(size 2.8194 1.5748)
			(drill oval 2.4384 1.1938)
			(layers "*.Cu" "*.Mask")
			(remove_unused_layers no)
			(net "GND")
			(clearance 0.127)
			(thermal_gap 0.127)
		)
		(pad "G2" thru_hole oval
			(at 0 3.875024)
			(size 2.8194 1.5748)
			(drill oval 2.4384 1.1938)
			(layers "*.Cu" "*.Mask")
			(remove_unused_layers no)
			(net "GND")
			(clearance 0.127)
			(thermal_gap 0.127)
		)
		(pad "G3" thru_hole oval
			(at 0 68.97497)
			(size 2.8194 1.5748)
			(drill oval 2.4384 1.1938)
			(layers "*.Cu" "*.Mask")
			(remove_unused_layers no)
			(net "GND")
			(clearance 0.127)
			(thermal_gap 0.127)
		)
	)
)
